FILE_TYPE = MACRO_DRAWING;
SET COLOR_WIRE YELLOW;
SET COLOR_PROP ORANGE;
SET COLOR_DOT WHITE;
SET COLOR_ARC YELLOW;
SET COLOR_BODY GREEN;
SET COLOR_NOTE PURPLE;
SET PROP_DISPLAY VALUE;
SET PAGE_NUMBER P133;
FORCEADD QUANTA_TITLE_BLOCK_C..1
(0 0);
FORCEPROP 1 LAST CUSTOM_TXT_CDS <NAME_2>
J 0
(-3175 50);
FORCEPROP 1 LAST CUSTOM_TXT_CDS <NAME_1>
J 0
(-3175 175);
FORCEPROP 1 LAST CUSTOM_TXT_CDS <Q_NUMBER>
J 0
(-1403 103);
DISPLAY 1.212766 (-1403 103);
FORCEPROP 1 LAST CUSTOM_TXT_CDS <Q_PROJ>
J 0
(-2382 102);
DISPLAY 1.212766 (-2382 102);
FORCEPROP 1 LAST CUSTOM_TXT_CDS <Q_REV>
J 0
(-184 103);
DISPLAY 1.212766 (-184 103);
FORCEPROP 1 LAST CUSTOM_TXT_CDS <CON_LAST_MODIFIED>
J 0
(-1885 15);
DISPLAY 0.978723 (-1885 15);
FORCEPROP 1 LAST CUSTOM_TXT_CDS <CON_PAGE_NUM> OF <CON_TOTAL_PAGES>
J 0
(-446 18);
DISPLAY 0.978723 (-446 18);
FORCEPROP 1 LAST Q_TITLE Blank
J 0
(-9300 75);
DISPLAY 2.446809 (-9300 75);
PAINT GREEN (-9300 75);
FORCEPROP 2 LAST CDS_LIB pure_quanta
J 0
(0 0);
DISPLAY INVISIBLE (0 0);
FORCEPROP 1 LAST CDS_LMAN_SYM_OUTLINE -9475,6775,100,-125
J 0
(0 0);
DISPLAY 0.468085 (0 0);
PAINT GREEN (0 0);
DISPLAY INVISIBLE (0 0);
FORCEPROP 2 LAST PAGE_BORDER TRUE
J 0
(-7890 5250);
DISPLAY 0.638298 (-7890 5250);
PAINT PINK (-7890 5250);
DISPLAY INVISIBLE (-7890 5250);
FORCEPROP 2 LAST CDS_XR_PAGE_TITLE CR-156 : @T6G_MB_LIB.T6G(SCH_1):PAGE156
J 0
(-7890 5250);
DISPLAY 0.638298 (-7890 5250);
PAINT PINK (-7890 5250);
DISPLAY INVISIBLE (-7890 5250);
FORCEPROP 2 LAST CUSTOM_TXT_CDS <XR_PAGE_TITLE>
J 0
(-7890 5250);
DISPLAY 0.638298 (-7890 5250);
PAINT PINK (-7890 5250);
DISPLAY INVISIBLE (-7890 5250);
FORCEPROP 1 LAST COMMENT_BODY TRUE
J 0
(12 -13);
DISPLAY 0.978723 (12 -13);
PAINT GREEN (12 -13);
DISPLAY INVISIBLE (12 -13);
FORCEPROP 1 LAST Q_DEPT BU9
J 1
(-3763 49);
DISPLAY 1.957447 (-3763 49);
PAINT GREEN (-3763 49);
DISPLAY INVISIBLE (-3763 49);
FORCEPROP 0 LAST CDS_CON_LAST_MODIFIED Thu Aug 24 10:14:43 2023
J 0
(-1885 15);
DISPLAY INVISIBLE (-1885 15);
QUIT
